(kicad_pcb
	(version 20260206)
	(generator "pcbnew")
	(generator_version "10.0")
	(general
		(thickness 1.6)
		(legacy_teardrops no)
	)
	(paper "A4")
	(title_block
		(title "panther-plus-userver — 13130-1b_20150205.brd")
		(comment 1 "Honey Badger (Wiwynn) / footprint 624 of 1509 (DIMM4), pads 184-190 of 210")
	)
	(layers
		(0 "F.Cu" signal "TOP")
		(4 "In1.Cu" signal "L2")
		(6 "In2.Cu" signal "L3")
		(8 "In3.Cu" signal "L4")
		(10 "In4.Cu" signal "L5")
		(12 "In5.Cu" signal "L6")
		(14 "In6.Cu" signal "L7")
		(16 "In7.Cu" signal "L8")
		(18 "In8.Cu" signal "L9")
		(20 "In9.Cu" signal "L10")
		(22 "In10.Cu" signal "L11")
		(2 "B.Cu" signal "BOTTOM")
		(9 "F.Adhes" user "F.Adhesive")
		(11 "B.Adhes" user "B.Adhesive")
		(13 "F.Paste" user "Package Geometry/Pastemask Top")
		(15 "B.Paste" user "Package Geometry/Pastemask Bottom")
		(5 "F.SilkS" user "Ref Des/Silkscreen Top")
		(7 "B.SilkS" user "Ref Des/Silkscreen Bottom")
		(1 "F.Mask" user "Board Geometry/Soldermask Top")
		(3 "B.Mask" user "Board Geometry/Soldermask Bottom")
		(17 "Dwgs.User" user "User.Drawings")
		(19 "Cmts.User" user "User.Comments")
		(21 "Eco1.User" user "User.Eco1")
		(23 "Eco2.User" user "User.Eco2")
		(25 "Edge.Cuts" user "Board Geometry/Outline")
		(27 "Margin" user)
		(31 "F.CrtYd" user "Package Geometry/Place Bound Top")
		(29 "B.CrtYd" user "Package Geometry/Place Bound Bottom")
		(35 "F.Fab" user "Ref Des/Assembly Top")
		(33 "B.Fab" user "Ref Des/Assembly Bottom")
	)
	(footprint ""
		(layer "F.Cu")
		(at 159.999934 -5.790692)
		(property "Reference" "DIMM4"
			(at 0 0 0)
			(layer "F.SilkS")
			(hide yes)
			(effects
				(font
					(size 1.27 1.27)
				)
			)
		)
		(property "Value" "DDR3-204P-174-COLAY-1-GP"
			(at -40.682164 -17.468088 0)
			(unlocked yes)
			(layer "F.Fab")
			(hide yes)
			(effects
				(font
					(size 1.016 1.016)
					(thickness 0.1524)
				)
			)
		)
		(property "Device Type" "AS0A626-H8SN-7H-COLAY-1"
			(at -40.682164 -18.992088 0)
			(unlocked yes)
			(layer "F.Fab")
			(hide yes)
			(effects
				(font
					(size 1.016 1.016)
					(thickness 0.1524)
				)
			)
		)
		(duplicate_pad_numbers_are_jumpers no)
		(pad "182" smd custom
			(at 25.049988 -4.106672)
			(size 0.1143 0.1143)
			(layers "F.Cu" "F.Mask" "F.Paste")
			(net "M_B_DQ57")
			(options
				(clearance outline)
				(anchor circle)
			)
			(primitives
				(gr_poly
					(pts
						(xy 0 0.9017) (xy -0.03175 0.89916) (xy -0.0635 0.889) (xy -0.09144 0.87376) (xy -0.11684 0.85344)
						(xy -0.13716 0.82804) (xy -0.1524 0.8001) (xy -0.16256 0.76835) (xy -0.1651 0.7366) (xy -0.1651 0.44958)
						(xy -0.17272 0.44196) (xy -0.19812 0.4064) (xy -0.2032 0.39624) (xy -0.20701 0.38735) (xy -0.21209 0.37719)
						(xy -0.2159 0.36703) (xy -0.21844 0.35687) (xy -0.22225 0.34544) (xy -0.22352 0.33528) (xy -0.22606 0.32512)
						(xy -0.22733 0.31369) (xy -0.22733 0.30353) (xy -0.2286 0.2921) (xy -0.22733 0.28067) (xy -0.22733 0.27051)
						(xy -0.22606 0.25908) (xy -0.22352 0.24892) (xy -0.22225 0.23876) (xy -0.21844 0.22733) (xy -0.2159 0.21717)
						(xy -0.21209 0.20701) (xy -0.20701 0.19685) (xy -0.2032 0.18796) (xy -0.19812 0.1778) (xy -0.17272 0.14224)
						(xy -0.1651 0.13462) (xy -0.1651 -0.7366) (xy -0.16256 -0.76835) (xy -0.1524 -0.8001) (xy -0.13716 -0.82804)
						(xy -0.11684 -0.85344) (xy -0.09144 -0.87376) (xy -0.0635 -0.889) (xy -0.03175 -0.89916) (xy 0 -0.9017)
						(xy 0.03175 -0.89916) (xy 0.0635 -0.889) (xy 0.09144 -0.87376) (xy 0.11684 -0.85344) (xy 0.13716 -0.82804)
						(xy 0.1524 -0.8001) (xy 0.16256 -0.76835) (xy 0.1651 -0.7366) (xy 0.1651 0.13462) (xy 0.17272 0.14224)
						(xy 0.19812 0.1778) (xy 0.2032 0.18796) (xy 0.20701 0.19685) (xy 0.21209 0.20701) (xy 0.2159 0.21717)
						(xy 0.21844 0.22733) (xy 0.22225 0.23876) (xy 0.22352 0.24892) (xy 0.22606 0.25908) (xy 0.22733 0.27051)
						(xy 0.22733 0.28067) (xy 0.2286 0.2921) (xy 0.22733 0.30353) (xy 0.22733 0.31369) (xy 0.22606 0.32512)
						(xy 0.22352 0.33528) (xy 0.22225 0.34544) (xy 0.21844 0.35687) (xy 0.2159 0.36703) (xy 0.21209 0.37719)
						(xy 0.20701 0.38735) (xy 0.2032 0.39624) (xy 0.19812 0.4064) (xy 0.17272 0.44196) (xy 0.1651 0.44958)
						(xy 0.1651 0.7366) (xy 0.16256 0.76835) (xy 0.1524 0.8001) (xy 0.13716 0.82804) (xy 0.11684 0.85344)
						(xy 0.09144 0.87376) (xy 0.0635 0.889) (xy 0.03175 0.89916)
					)
					(width 0)
					(fill yes)
				)
			)
		)
		(pad "183" smd custom
			(at 25.349962 4.106672)
			(size 0.1143 0.1143)
			(layers "F.Cu" "F.Mask" "F.Paste")
			(net "M_B_DQ60")
			(options
				(clearance outline)
				(anchor circle)
			)
			(primitives
				(gr_poly
					(pts
						(xy 0 0.9017) (xy -0.03175 0.89916) (xy -0.0635 0.889) (xy -0.09144 0.87376) (xy -0.11684 0.85344)
						(xy -0.13716 0.82804) (xy -0.1524 0.8001) (xy -0.16256 0.76835) (xy -0.1651 0.7366) (xy -0.1651 0.11938)
						(xy -0.17272 0.11176) (xy -0.19812 0.0762) (xy -0.2032 0.06604) (xy -0.20701 0.05715) (xy -0.21209 0.04699)
						(xy -0.2159 0.03683) (xy -0.21844 0.02667) (xy -0.22225 0.01524) (xy -0.22352 0.00508) (xy -0.22606 -0.00508)
						(xy -0.22733 -0.01651) (xy -0.22733 -0.02667) (xy -0.2286 -0.0381) (xy -0.22733 -0.04953) (xy -0.22733 -0.05969)
						(xy -0.22606 -0.07112) (xy -0.22352 -0.08128) (xy -0.22225 -0.09144) (xy -0.21844 -0.10287) (xy -0.2159 -0.11303)
						(xy -0.21209 -0.12319) (xy -0.20701 -0.13335) (xy -0.2032 -0.14224) (xy -0.19812 -0.1524) (xy -0.17272 -0.18796)
						(xy -0.1651 -0.19558) (xy -0.1651 -0.7366) (xy -0.16256 -0.76835) (xy -0.1524 -0.8001) (xy -0.13716 -0.82804)
						(xy -0.11684 -0.85344) (xy -0.09144 -0.87376) (xy -0.0635 -0.889) (xy -0.03175 -0.89916) (xy 0 -0.9017)
						(xy 0.03175 -0.89916) (xy 0.0635 -0.889) (xy 0.09144 -0.87376) (xy 0.11684 -0.85344) (xy 0.13716 -0.82804)
						(xy 0.1524 -0.8001) (xy 0.16256 -0.76835) (xy 0.1651 -0.7366) (xy 0.1651 -0.19685) (xy 0.17272 -0.18923)
						(xy 0.17907 -0.18034) (xy 0.18669 -0.17145) (xy 0.19177 -0.16256) (xy 0.19812 -0.15367) (xy 0.20828 -0.13335)
						(xy 0.21971 -0.10287) (xy 0.22225 -0.09271) (xy 0.22479 -0.08128) (xy 0.22606 -0.07112) (xy 0.2286 -0.05969)
						(xy 0.2286 -0.01651) (xy 0.22606 -0.00508) (xy 0.22479 0.00508) (xy 0.22225 0.01651) (xy 0.21971 0.02667)
						(xy 0.20828 0.05715) (xy 0.19812 0.07747) (xy 0.19177 0.08636) (xy 0.18669 0.09525) (xy 0.17907 0.10414)
						(xy 0.17272 0.11303) (xy 0.1651 0.12065) (xy 0.1651 0.7366) (xy 0.16256 0.76835) (xy 0.1524 0.8001)
						(xy 0.13716 0.82804) (xy 0.11684 0.85344) (xy 0.09144 0.87376) (xy 0.0635 0.889) (xy 0.03175 0.89916)
					)
					(width 0)
					(fill yes)
				)
			)
		)
		(pad "184" smd custom
			(at 25.649936 -4.106672)
			(size 0.1143 0.1143)
			(layers "F.Cu" "F.Mask" "F.Paste")
			(net "GND")
			(options
				(clearance outline)
				(anchor circle)
			)
			(primitives
				(gr_poly
					(pts
						(xy 0 0.9017) (xy -0.03175 0.89916) (xy -0.0635 0.889) (xy -0.09144 0.87376) (xy -0.11684 0.85344)
						(xy -0.13716 0.82804) (xy -0.1524 0.8001) (xy -0.16256 0.76835) (xy -0.1651 0.7366) (xy -0.1651 0.19685)
						(xy -0.17272 0.18923) (xy -0.17907 0.18034) (xy -0.18669 0.17145) (xy -0.19177 0.16256) (xy -0.19812 0.15367)
						(xy -0.20828 0.13335) (xy -0.21971 0.10287) (xy -0.22225 0.09271) (xy -0.22479 0.08128) (xy -0.22606 0.07112)
						(xy -0.2286 0.05969) (xy -0.2286 0.01651) (xy -0.22606 0.00508) (xy -0.22479 -0.00508) (xy -0.22225 -0.01651)
						(xy -0.21971 -0.02667) (xy -0.20828 -0.05715) (xy -0.19812 -0.07747) (xy -0.19177 -0.08636) (xy -0.18669 -0.09525)
						(xy -0.17907 -0.10414) (xy -0.17272 -0.11303) (xy -0.1651 -0.12065) (xy -0.1651 -0.7366) (xy -0.16256 -0.76835)
						(xy -0.1524 -0.8001) (xy -0.13716 -0.82804) (xy -0.11684 -0.85344) (xy -0.09144 -0.87376) (xy -0.0635 -0.889)
						(xy -0.03175 -0.89916) (xy 0 -0.9017) (xy 0.03175 -0.89916) (xy 0.0635 -0.889) (xy 0.09144 -0.87376)
						(xy 0.11684 -0.85344) (xy 0.13716 -0.82804) (xy 0.1524 -0.8001) (xy 0.16256 -0.76835) (xy 0.1651 -0.7366)
						(xy 0.1651 -0.11938) (xy 0.17272 -0.11176) (xy 0.19812 -0.0762) (xy 0.2032 -0.06604) (xy 0.20701 -0.05715)
						(xy 0.21209 -0.04699) (xy 0.2159 -0.03683) (xy 0.21844 -0.02667) (xy 0.22225 -0.01524) (xy 0.22352 -0.00508)
						(xy 0.22606 0.00508) (xy 0.22733 0.01651) (xy 0.22733 0.02667) (xy 0.2286 0.0381) (xy 0.22733 0.04953)
						(xy 0.22733 0.05969) (xy 0.22606 0.07112) (xy 0.22352 0.08128) (xy 0.22225 0.09144) (xy 0.21844 0.10287)
						(xy 0.2159 0.11303) (xy 0.21209 0.12319) (xy 0.20701 0.13335) (xy 0.2032 0.14224) (xy 0.19812 0.1524)
						(xy 0.17272 0.18796) (xy 0.1651 0.19558) (xy 0.1651 0.7366) (xy 0.16256 0.76835) (xy 0.1524 0.8001)
						(xy 0.13716 0.82804) (xy 0.11684 0.85344) (xy 0.09144 0.87376) (xy 0.0635 0.889) (xy 0.03175 0.89916)
					)
					(width 0)
					(fill yes)
				)
			)
		)
		(pad "185" smd custom
			(at 25.94991 4.106672)
			(size 0.1143 0.1143)
			(layers "F.Cu" "F.Mask" "F.Paste")
			(net "M_B_DQ61")
			(options
				(clearance outline)
				(anchor circle)
			)
			(primitives
				(gr_poly
					(pts
						(xy 0 0.9017) (xy -0.03175 0.89916) (xy -0.0635 0.889) (xy -0.09144 0.87376) (xy -0.11684 0.85344)
						(xy -0.13716 0.82804) (xy -0.1524 0.8001) (xy -0.16256 0.76835) (xy -0.1651 0.7366) (xy -0.1651 -0.13462)
						(xy -0.17272 -0.14224) (xy -0.19812 -0.1778) (xy -0.2032 -0.18796) (xy -0.20701 -0.19685) (xy -0.21209 -0.20701)
						(xy -0.2159 -0.21717) (xy -0.21844 -0.22733) (xy -0.22225 -0.23876) (xy -0.22352 -0.24892) (xy -0.22606 -0.25908)
						(xy -0.22733 -0.27051) (xy -0.22733 -0.28067) (xy -0.2286 -0.2921) (xy -0.22733 -0.30353) (xy -0.22733 -0.31369)
						(xy -0.22606 -0.32512) (xy -0.22352 -0.33528) (xy -0.22225 -0.34544) (xy -0.21844 -0.35687) (xy -0.2159 -0.36703)
						(xy -0.21209 -0.37719) (xy -0.20701 -0.38735) (xy -0.2032 -0.39624) (xy -0.19812 -0.4064) (xy -0.17272 -0.44196)
						(xy -0.1651 -0.44958) (xy -0.1651 -0.7366) (xy -0.16256 -0.76835) (xy -0.1524 -0.8001) (xy -0.13716 -0.82804)
						(xy -0.11684 -0.85344) (xy -0.09144 -0.87376) (xy -0.0635 -0.889) (xy -0.03175 -0.89916) (xy 0 -0.9017)
						(xy 0.03175 -0.89916) (xy 0.0635 -0.889) (xy 0.09144 -0.87376) (xy 0.11684 -0.85344) (xy 0.13716 -0.82804)
						(xy 0.1524 -0.8001) (xy 0.16256 -0.76835) (xy 0.1651 -0.7366) (xy 0.1651 -0.44958) (xy 0.17272 -0.44196)
						(xy 0.19812 -0.4064) (xy 0.2032 -0.39624) (xy 0.20701 -0.38735) (xy 0.21209 -0.37719) (xy 0.2159 -0.36703)
						(xy 0.21844 -0.35687) (xy 0.22225 -0.34544) (xy 0.22352 -0.33528) (xy 0.22606 -0.32512) (xy 0.22733 -0.31369)
						(xy 0.22733 -0.30353) (xy 0.2286 -0.2921) (xy 0.22733 -0.28067) (xy 0.22733 -0.27051) (xy 0.22606 -0.25908)
						(xy 0.22352 -0.24892) (xy 0.22225 -0.23876) (xy 0.21844 -0.22733) (xy 0.2159 -0.21717) (xy 0.21209 -0.20701)
						(xy 0.20701 -0.19685) (xy 0.2032 -0.18796) (xy 0.19812 -0.1778) (xy 0.17272 -0.14224) (xy 0.1651 -0.13462)
						(xy 0.1651 0.7366) (xy 0.16256 0.76835) (xy 0.1524 0.8001) (xy 0.13716 0.82804) (xy 0.11684 0.85344)
						(xy 0.09144 0.87376) (xy 0.0635 0.889) (xy 0.03175 0.89916)
					)
					(width 0)
					(fill yes)
				)
			)
		)
		(pad "186" smd custom
			(at 26.249884 -4.106672)
			(size 0.1143 0.1143)
			(layers "F.Cu" "F.Mask" "F.Paste")
			(net "M_B_DQS_DN7")
			(options
				(clearance outline)
				(anchor circle)
			)
			(primitives
				(gr_poly
					(pts
						(xy 0 0.9017) (xy -0.03175 0.89916) (xy -0.0635 0.889) (xy -0.09144 0.87376) (xy -0.11684 0.85344)
						(xy -0.13716 0.82804) (xy -0.1524 0.8001) (xy -0.16256 0.76835) (xy -0.1651 0.7366) (xy -0.1651 0.44958)
						(xy -0.17272 0.44196) (xy -0.19812 0.4064) (xy -0.2032 0.39624) (xy -0.20701 0.38735) (xy -0.21209 0.37719)
						(xy -0.2159 0.36703) (xy -0.21844 0.35687) (xy -0.22225 0.34544) (xy -0.22352 0.33528) (xy -0.22606 0.32512)
						(xy -0.22733 0.31369) (xy -0.22733 0.30353) (xy -0.2286 0.2921) (xy -0.22733 0.28067) (xy -0.22733 0.27051)
						(xy -0.22606 0.25908) (xy -0.22352 0.24892) (xy -0.22225 0.23876) (xy -0.21844 0.22733) (xy -0.2159 0.21717)
						(xy -0.21209 0.20701) (xy -0.20701 0.19685) (xy -0.2032 0.18796) (xy -0.19812 0.1778) (xy -0.17272 0.14224)
						(xy -0.1651 0.13462) (xy -0.1651 -0.7366) (xy -0.16256 -0.76835) (xy -0.1524 -0.8001) (xy -0.13716 -0.82804)
						(xy -0.11684 -0.85344) (xy -0.09144 -0.87376) (xy -0.0635 -0.889) (xy -0.03175 -0.89916) (xy 0 -0.9017)
						(xy 0.03175 -0.89916) (xy 0.0635 -0.889) (xy 0.09144 -0.87376) (xy 0.11684 -0.85344) (xy 0.13716 -0.82804)
						(xy 0.1524 -0.8001) (xy 0.16256 -0.76835) (xy 0.1651 -0.7366) (xy 0.1651 0.13462) (xy 0.17272 0.14224)
						(xy 0.19812 0.1778) (xy 0.2032 0.18796) (xy 0.20701 0.19685) (xy 0.21209 0.20701) (xy 0.2159 0.21717)
						(xy 0.21844 0.22733) (xy 0.22225 0.23876) (xy 0.22352 0.24892) (xy 0.22606 0.25908) (xy 0.22733 0.27051)
						(xy 0.22733 0.28067) (xy 0.2286 0.2921) (xy 0.22733 0.30353) (xy 0.22733 0.31369) (xy 0.22606 0.32512)
						(xy 0.22352 0.33528) (xy 0.22225 0.34544) (xy 0.21844 0.35687) (xy 0.2159 0.36703) (xy 0.21209 0.37719)
						(xy 0.20701 0.38735) (xy 0.2032 0.39624) (xy 0.19812 0.4064) (xy 0.17272 0.44196) (xy 0.1651 0.44958)
						(xy 0.1651 0.7366) (xy 0.16256 0.76835) (xy 0.1524 0.8001) (xy 0.13716 0.82804) (xy 0.11684 0.85344)
						(xy 0.09144 0.87376) (xy 0.0635 0.889) (xy 0.03175 0.89916)
					)
					(width 0)
					(fill yes)
				)
			)
		)
		(pad "187" smd custom
			(at 26.550112 4.106672)
			(size 0.1143 0.1143)
			(layers "F.Cu" "F.Mask" "F.Paste")
			(net "GND")
			(options
				(clearance outline)
				(anchor circle)
			)
			(primitives
				(gr_poly
					(pts
						(xy 0 0.9017) (xy -0.03175 0.89916) (xy -0.0635 0.889) (xy -0.09144 0.87376) (xy -0.11684 0.85344)
						(xy -0.13716 0.82804) (xy -0.1524 0.8001) (xy -0.16256 0.76835) (xy -0.1651 0.7366) (xy -0.1651 0.11938)
						(xy -0.17272 0.11176) (xy -0.19812 0.0762) (xy -0.2032 0.06604) (xy -0.20701 0.05715) (xy -0.21209 0.04699)
						(xy -0.2159 0.03683) (xy -0.21844 0.02667) (xy -0.22225 0.01524) (xy -0.22352 0.00508) (xy -0.22606 -0.00508)
						(xy -0.22733 -0.01651) (xy -0.22733 -0.02667) (xy -0.2286 -0.0381) (xy -0.22733 -0.04953) (xy -0.22733 -0.05969)
						(xy -0.22606 -0.07112) (xy -0.22352 -0.08128) (xy -0.22225 -0.09144) (xy -0.21844 -0.10287) (xy -0.2159 -0.11303)
						(xy -0.21209 -0.12319) (xy -0.20701 -0.13335) (xy -0.2032 -0.14224) (xy -0.19812 -0.1524) (xy -0.17272 -0.18796)
						(xy -0.1651 -0.19558) (xy -0.1651 -0.7366) (xy -0.16256 -0.76835) (xy -0.1524 -0.8001) (xy -0.13716 -0.82804)
						(xy -0.11684 -0.85344) (xy -0.09144 -0.87376) (xy -0.0635 -0.889) (xy -0.03175 -0.89916) (xy 0 -0.9017)
						(xy 0.03175 -0.89916) (xy 0.0635 -0.889) (xy 0.09144 -0.87376) (xy 0.11684 -0.85344) (xy 0.13716 -0.82804)
						(xy 0.1524 -0.8001) (xy 0.16256 -0.76835) (xy 0.1651 -0.7366) (xy 0.1651 -0.19685) (xy 0.17272 -0.18923)
						(xy 0.17907 -0.18034) (xy 0.18669 -0.17145) (xy 0.19177 -0.16256) (xy 0.19812 -0.15367) (xy 0.20828 -0.13335)
						(xy 0.21971 -0.10287) (xy 0.22225 -0.09271) (xy 0.22479 -0.08128) (xy 0.22606 -0.07112) (xy 0.2286 -0.05969)
						(xy 0.2286 -0.01651) (xy 0.22606 -0.00508) (xy 0.22479 0.00508) (xy 0.22225 0.01651) (xy 0.21971 0.02667)
						(xy 0.20828 0.05715) (xy 0.19812 0.07747) (xy 0.19177 0.08636) (xy 0.18669 0.09525) (xy 0.17907 0.10414)
						(xy 0.17272 0.11303) (xy 0.1651 0.12065) (xy 0.1651 0.7366) (xy 0.16256 0.76835) (xy 0.1524 0.8001)
						(xy 0.13716 0.82804) (xy 0.11684 0.85344) (xy 0.09144 0.87376) (xy 0.0635 0.889) (xy 0.03175 0.89916)
					)
					(width 0)
					(fill yes)
				)
			)
		)
		(pad "188" smd custom
			(at 26.850086 -4.106672)
			(size 0.1143 0.1143)
			(layers "F.Cu" "F.Mask" "F.Paste")
			(net "M_B_DQS_DP7")
			(options
				(clearance outline)
				(anchor circle)
			)
			(primitives
				(gr_poly
					(pts
						(xy 0 0.9017) (xy -0.03175 0.89916) (xy -0.0635 0.889) (xy -0.09144 0.87376) (xy -0.11684 0.85344)
						(xy -0.13716 0.82804) (xy -0.1524 0.8001) (xy -0.16256 0.76835) (xy -0.1651 0.7366) (xy -0.1651 0.19685)
						(xy -0.17272 0.18923) (xy -0.17907 0.18034) (xy -0.18669 0.17145) (xy -0.19177 0.16256) (xy -0.19812 0.15367)
						(xy -0.20828 0.13335) (xy -0.21971 0.10287) (xy -0.22225 0.09271) (xy -0.22479 0.08128) (xy -0.22606 0.07112)
						(xy -0.2286 0.05969) (xy -0.2286 0.01651) (xy -0.22606 0.00508) (xy -0.22479 -0.00508) (xy -0.22225 -0.01651)
						(xy -0.21971 -0.02667) (xy -0.20828 -0.05715) (xy -0.19812 -0.07747) (xy -0.19177 -0.08636) (xy -0.18669 -0.09525)
						(xy -0.17907 -0.10414) (xy -0.17272 -0.11303) (xy -0.1651 -0.12065) (xy -0.1651 -0.7366) (xy -0.16256 -0.76835)
						(xy -0.1524 -0.8001) (xy -0.13716 -0.82804) (xy -0.11684 -0.85344) (xy -0.09144 -0.87376) (xy -0.0635 -0.889)
						(xy -0.03175 -0.89916) (xy 0 -0.9017) (xy 0.03175 -0.89916) (xy 0.0635 -0.889) (xy 0.09144 -0.87376)
						(xy 0.11684 -0.85344) (xy 0.13716 -0.82804) (xy 0.1524 -0.8001) (xy 0.16256 -0.76835) (xy 0.1651 -0.7366)
						(xy 0.1651 -0.11938) (xy 0.17272 -0.11176) (xy 0.19812 -0.0762) (xy 0.2032 -0.06604) (xy 0.20701 -0.05715)
						(xy 0.21209 -0.04699) (xy 0.2159 -0.03683) (xy 0.21844 -0.02667) (xy 0.22225 -0.01524) (xy 0.22352 -0.00508)
						(xy 0.22606 0.00508) (xy 0.22733 0.01651) (xy 0.22733 0.02667) (xy 0.2286 0.0381) (xy 0.22733 0.04953)
						(xy 0.22733 0.05969) (xy 0.22606 0.07112) (xy 0.22352 0.08128) (xy 0.22225 0.09144) (xy 0.21844 0.10287)
						(xy 0.2159 0.11303) (xy 0.21209 0.12319) (xy 0.20701 0.13335) (xy 0.2032 0.14224) (xy 0.19812 0.1524)
						(xy 0.17272 0.18796) (xy 0.1651 0.19558) (xy 0.1651 0.7366) (xy 0.16256 0.76835) (xy 0.1524 0.8001)
						(xy 0.13716 0.82804) (xy 0.11684 0.85344) (xy 0.09144 0.87376) (xy 0.0635 0.889) (xy 0.03175 0.89916)
					)
					(width 0)
					(fill yes)
				)
			)
		)
	)
)
